#ISCELL
  mstr_misc dns *
  *
#ISCELL
  mstr_symbols design_note *
  *
#ISCELL
  mstr_symbols intel_corp_bpage *
  *
#ISCELL
  mstr_symbols gnd *
  page218_i1
#ISCELL
  mstr_standard offpage *
  page218_i10
#ISCELL
  mstr_standard offpage *
  page218_i11
#ISCELL
  mstr_standard offpage *
  page218_i12
#CELL
  mstr_discrete res *
  page218_i13
#CELL
  mstr_discrete cap *
  page218_i14
#CELL
  mstr_discrete res *
  page218_i15
#CELL
  mstr_discrete cap *
  page218_i16
#CELL
  w_hdl sc22p50v2jn-4gp *
  page218_i17
#CELL
  mstr_discrete res *
  page218_i18
#CELL
  mstr_discrete res *
  page218_i19
#ISCELL
  mstr_standard offpage *
  page218_i2
#CELL
  w_hdl sc22p50v2jn-4gp *
  page218_i20
#CELL
  mstr_discrete res *
  page218_i21
#ISCELL
  mstr_symbols pvccio_cpu0 *
  page218_i23
#ISCELL
  mstr_symbols gnd *
  page218_i24
#ISCELL
  mstr_symbols gnd *
  page218_i25
#ISCELL
  mstr_symbols gnd *
  page218_i26
#ISCELL
  mstr_symbols gnd *
  page218_i27
#CELL
  dev_discrete cap_a *
  page218_i28
#ISCELL
  mstr_symbols gnd *
  page218_i29
#ISCELL
  mstr_standard offpage *
  page218_i3
#CELL
  dev_discrete cap_a *
  page218_i30
#ISCELL
  mstr_symbols gnd *
  page218_i33
#CELL
  mstr_discrete res *
  page218_i34
#CELL
  mstr_discrete res *
  page218_i35
#ISCELL
  mstr_symbols p3v3_stby *
  page218_i36
#ISCELL
  mstr_symbols gnd *
  page218_i37
#CELL
  dev_discrete cap_a *
  page218_i38
#ISCELL
  mstr_symbols gnd *
  page218_i39
#ISCELL
  mstr_standard offpage *
  page218_i4
#CELL
  dev_discrete cap_a *
  page218_i40
#CELL
  mstr_discrete cap *
  page218_i41
#ISCELL
  mstr_symbols gnd *
  page218_i42
#CELL
  mstr_discrete res *
  page218_i45
#CELL
  mstr_discrete res *
  page218_i46
#ISCELL
  mstr_standard offpage *
  page218_i48
#ISCELL
  mstr_standard offpage *
  page218_i49
#ISCELL
  mstr_standard offpage *
  page218_i5
#ISCELL
  mstr_standard offpage *
  page218_i50
#ISCELL
  mstr_standard offpage *
  page218_i51
#ISCELL
  mstr_standard offpage *
  page218_i52
#ISCELL
  mstr_standard offpage *
  page218_i53
#ISCELL
  mstr_standard offpage *
  page218_i54
#CELL
  mstr_discrete res *
  page218_i55
#CELL
  mstr_discrete res *
  page218_i56
#CELL
  mstr_discrete res *
  page218_i57
#CELL
  mstr_discrete res *
  page218_i58
#CELL
  mstr_discrete res *
  page218_i59
#ISCELL
  mstr_standard offpage *
  page218_i6
#CELL
  mstr_discrete res *
  page218_i60
#ISCELL
  mstr_standard offpage *
  page218_i61
#ISCELL
  mstr_symbols p3v3_stby *
  page218_i62
#ISCELL
  mstr_standard offpage *
  page218_i64
#ISCELL
  mstr_standard offpage *
  page218_i65
#ISCELL
  mstr_standard offpage *
  page218_i66
#CELL
  mstr_discrete res *
  page218_i67
#ISCELL
  mstr_symbols pvccio_cpu0 *
  page218_i68
#CELL
  mstr_controller pxm1310b *
  page218_i69
#ISCELL
  mstr_standard offpage *
  page218_i7
#CELL
  mstr_discrete res *
  page218_i70
#CELL
  mstr_discrete res *
  page218_i73
#CELL
  mstr_discrete res *
  page218_i74
#CELL
  mstr_discrete res *
  page218_i75
#CELL
  mstr_discrete res *
  page218_i76
#ISCELL
  mstr_standard offpage *
  page218_i8
#ISCELL
  mstr_standard offpage *
  page218_i9
